FILE_TYPE=LIBRARY_PARTS;
primitive 'MP5990GMA1111Z';
  pin
    'VOUT3':
      PIN_NUMBER='(29)';
      OUTPUT_LOAD='(1.0,-1.0)';
    'VOUT2':
      PIN_NUMBER='(28)';
      OUTPUT_LOAD='(1.0,-1.0)';
    'VOUT1':
      PIN_NUMBER='(27)';
      OUTPUT_LOAD='(1.0,-1.0)';
    'VIN2':
      PIN_NUMBER='(2)';
      INPUT_LOAD='(-0.01,0.01)';
    'EN':
      PIN_NUMBER='(26)';
      INPUT_LOAD='(-0.01,0.01)';
    'VIN3':
      PIN_NUMBER='(3)';
      INPUT_LOAD='(-0.01,0.01)';
    'VIN4':
      PIN_NUMBER='(4)';
      INPUT_LOAD='(-0.01,0.01)';
    'GND1':
      PIN_NUMBER='(18)';
      PINUSE='POWER';
      NO_LOAD_CHECK='Both';
      NO_IO_CHECK='Both';
      NO_ASSERT_CHECK='TRUE';
      NO_DIR_CHECK='TRUE';
      ALLOW_CONNECT='TRUE';
    'SDA':
      PIN_NUMBER='(12)';
      BIDIRECTIONAL='TRUE';
      INPUT_LOAD='(-0.01,0.01)';
      OUTPUT_LOAD='(1.0,-1.0)';
    'VIN_UVW#':
      PIN_NUMBER='(14)';
      OUTPUT_LOAD='(1.0,-1.0)';
    'SCL':
      PIN_NUMBER='(11)';
      INPUT_LOAD='(-0.01,0.01)';
    'D_OC':
      PIN_NUMBER='(37)';
      OUTPUT_LOAD='(1.0,-1.0)';
    'VOUT5':
      PIN_NUMBER='(31)';
      OUTPUT_LOAD='(1.0,-1.0)';
    'VOUT9':
      PIN_NUMBER='(35)';
      OUTPUT_LOAD='(1.0,-1.0)';
    'ALT#':
      PIN_NUMBER='(10)';
      OUTPUT_LOAD='(1.0,-1.0)';
    'GOK':
      PIN_NUMBER='(39)';
      BIDIRECTIONAL='TRUE';
      INPUT_LOAD='(-0.01,0.01)';
      OUTPUT_LOAD='(1.0,-1.0)';
    'VIN7':
      PIN_NUMBER='(7)';
      INPUT_LOAD='(-0.01,0.01)';
    'VOUT7':
      PIN_NUMBER='(33)';
      OUTPUT_LOAD='(1.0,-1.0)';
    'MODE':
      PIN_NUMBER='(41)';
      INPUT_LOAD='(-0.01,0.01)';
    'VIN8':
      PIN_NUMBER='(8)';
      INPUT_LOAD='(-0.01,0.01)';
    'PG||OCW#':
      PIN_NUMBER='(13)';
      OUTPUT_LOAD='(1.0,-1.0)';
    'VOUT8':
      PIN_NUMBER='(34)';
      OUTPUT_LOAD='(1.0,-1.0)';
    'ON':
      PIN_NUMBER='(38)';
      OUTPUT_LOAD='(1.0,-1.0)';
    'VIN5':
      PIN_NUMBER='(5)';
      INPUT_LOAD='(-0.01,0.01)';
    'VIN6':
      PIN_NUMBER='(6)';
      INPUT_LOAD='(-0.01,0.01)';
    'VTEMP':
      PIN_NUMBER='(15)';
      INPUT_LOAD='(-0.01,0.01)';
    'OCREF':
      PIN_NUMBER='(22)';
      OUTPUT_LOAD='(1.0,-1.0)';
    'SCREF_OCWREF':
      PIN_NUMBER='(25)';
      OUTPUT_LOAD='(1.0,-1.0)';
    'SS':
      PIN_NUMBER='(16)';
      OUTPUT_LOAD='(1.0,-1.0)';
    'VOUT6':
      PIN_NUMBER='(32)';
      OUTPUT_LOAD='(1.0,-1.0)';
    'IMON':
      PIN_NUMBER='(21)';
      BIDIRECTIONAL='TRUE';
      INPUT_LOAD='(-0.01,0.01)';
      OUTPUT_LOAD='(1.0,-1.0)';
    'CS':
      PIN_NUMBER='(20)';
      OUTPUT_LOAD='(1.0,-1.0)';
    'VIN9':
      PIN_NUMBER='(42)';
      INPUT_LOAD='(-0.01,0.01)';
    'VOUT10':
      PIN_NUMBER='(36)';
      OUTPUT_LOAD='(1.0,-1.0)';
    'VOSEN':
      PIN_NUMBER='(24)';
      INPUT_LOAD='(-0.01,0.01)';
    'VOUT4':
      PIN_NUMBER='(30)';
      OUTPUT_LOAD='(1.0,-1.0)';
    'VIN1':
      PIN_NUMBER='(1)';
      INPUT_LOAD='(-0.01,0.01)';
    'GND2':
      PIN_NUMBER='(44)';
      PINUSE='POWER';
      NO_LOAD_CHECK='Both';
      NO_IO_CHECK='Both';
      NO_ASSERT_CHECK='TRUE';
      NO_DIR_CHECK='TRUE';
      ALLOW_CONNECT='TRUE';
    'FLT_TYPE':
      PIN_NUMBER='(40)';
      INPUT_LOAD='(-0.01,0.01)';
    'VIN10':
      PIN_NUMBER='(43)';
      INPUT_LOAD='(-0.01,0.01)';
    'VINSEN':
      PIN_NUMBER='(9)';
      INPUT_LOAD='(-0.01,0.01)';
    'VDD33_1':
      PIN_NUMBER='(17)';
      PINUSE='POWER';
      NO_LOAD_CHECK='Both';
      NO_IO_CHECK='Both';
      NO_ASSERT_CHECK='TRUE';
      NO_DIR_CHECK='TRUE';
      ALLOW_CONNECT='TRUE';
    'VDD33_2':
      PIN_NUMBER='(45)';
      PINUSE='POWER';
      NO_LOAD_CHECK='Both';
      NO_IO_CHECK='Both';
      NO_ASSERT_CHECK='TRUE';
      NO_DIR_CHECK='TRUE';
      ALLOW_CONNECT='TRUE';
    'VDD18':
      PIN_NUMBER='(19)';
      PINUSE='POWER';
      NO_LOAD_CHECK='Both';
      NO_IO_CHECK='Both';
      NO_ASSERT_CHECK='TRUE';
      NO_DIR_CHECK='TRUE';
      ALLOW_CONNECT='TRUE';
    'ADDR':
      PIN_NUMBER='(23)';
      INPUT_LOAD='(-0.01,0.01)';
  end_pin;
  body
    PART_NAME='MP5990GMA1111Z';
    BODY_NAME='MP5990GMA1111Z';
    PHYS_DES_PREFIX='U';
    CLASS='IC';
  end_body;
end_primitive;

END.
